(kicad_pcb
	(version 20241229)
	(generator "pcbnew")
	(generator_version "9.0")
	(general
		(thickness 1.62)
		(legacy_teardrops no)
	)
	(paper "A4")
	(title_block
		(title "OCuLink to 10GbE adapter")
		(date "2026-02-23")
		(rev "1.1.0")
		(company "Antmicro Ltd")
		(comment 1 "www.antmicro.com")
		(comment 9 "footprints 90-95 of 510")
	)
	(layers
		(0 "F.Cu" signal)
		(4 "In1.Cu" signal)
		(6 "In2.Cu" signal)
		(8 "In3.Cu" signal)
		(10 "In4.Cu" signal)
		(12 "In5.Cu" signal)
		(14 "In6.Cu" signal)
		(2 "B.Cu" signal)
		(9 "F.Adhes" user "F.Adhesive")
		(11 "B.Adhes" user "B.Adhesive")
		(13 "F.Paste" user)
		(15 "B.Paste" user)
		(5 "F.SilkS" user "F.Silkscreen")
		(7 "B.SilkS" user "B.Silkscreen")
		(1 "F.Mask" user)
		(3 "B.Mask" user)
		(17 "Dwgs.User" user "User.Drawings")
		(19 "Cmts.User" user "User.Comments")
		(21 "Eco1.User" user "User.Eco1")
		(23 "Eco2.User" user "User.Eco2")
		(25 "Edge.Cuts" user)
		(27 "Margin" user)
		(31 "F.CrtYd" user "F.Courtyard")
		(29 "B.CrtYd" user "B.Courtyard")
		(35 "F.Fab" user)
		(33 "B.Fab" user)
	)
	(footprint "antmicro-footprints:C_0805_2012Metric"
		(layer "F.Cu")
		(at 69.45 114.3 90)
		(descr "Capacitor SMD 0805")
		(tags "capacitor SMD 0805")
		(property "Reference" "C173"
			(at -2.4 5.33 90)
			(layer "F.SilkS")
			(effects
				(font
					(size 0.7 0.7)
					(thickness 0.15)
				)
				(justify left bottom)
			)
		)
		(property "Value" "C_100u_0805"
			(at -2.055717 1.963153 90)
			(layer "F.Fab")
			(hide yes)
			(effects
				(font
					(size 0.7 0.7)
					(thickness 0.15)
				)
				(justify left bottom)
			)
		)
		(property "Datasheet" "https://www.murata.com/products/productdetail?partno=GRM21BR60J107ME15%23"
			(at 0 0 90)
			(layer "F.Fab")
			(hide yes)
			(effects
				(font
					(size 1.27 1.27)
					(thickness 0.15)
				)
			)
		)
		(property "Description" "SMD Multilayer Ceramic Capacitor, 100 µF, 6.3 V, 0805 [2012 Metric], ± 20%, X5R, GRM Series"
			(at 0 0 90)
			(layer "F.Fab")
			(hide yes)
			(effects
				(font
					(size 1.27 1.27)
					(thickness 0.15)
				)
			)
		)
		(property "MPN" "GRM21BR60J107ME15L"
			(at 0 0 90)
			(unlocked yes)
			(layer "F.Fab")
			(hide yes)
			(effects
				(font
					(size 1 1)
					(thickness 0.15)
				)
			)
		)
		(property "Manufacturer" "Murata"
			(at 0 0 90)
			(unlocked yes)
			(layer "F.Fab")
			(hide yes)
			(effects
				(font
					(size 1 1)
					(thickness 0.15)
				)
			)
		)
		(property "License" "Apache-2.0"
			(at 0 0 90)
			(unlocked yes)
			(layer "F.Fab")
			(hide yes)
			(effects
				(font
					(size 1 1)
					(thickness 0.15)
				)
			)
		)
		(property "Author" "Antmicro"
			(at 0 0 90)
			(unlocked yes)
			(layer "F.Fab")
			(hide yes)
			(effects
				(font
					(size 1 1)
					(thickness 0.15)
				)
			)
		)
		(property "Val" "100u"
			(at 0 0 90)
			(unlocked yes)
			(layer "F.Fab")
			(hide yes)
			(effects
				(font
					(size 1 1)
					(thickness 0.15)
				)
			)
		)
		(property "Voltage" ""
			(at 0 0 90)
			(unlocked yes)
			(layer "F.Fab")
			(hide yes)
			(effects
				(font
					(size 1 1)
					(thickness 0.15)
				)
			)
		)
		(property "Dielectric" ""
			(at 0 0 90)
			(unlocked yes)
			(layer "F.Fab")
			(hide yes)
			(effects
				(font
					(size 1 1)
					(thickness 0.15)
				)
			)
		)
		(property "Public" "False"
			(at 0 0 90)
			(unlocked yes)
			(layer "F.Fab")
			(hide yes)
			(effects
				(font
					(size 1 1)
					(thickness 0.15)
				)
			)
		)
		(sheetname "/X710-AT2 power/")
		(sheetfile "x710-at2-power.kicad_sch")
		(attr smd)
		(fp_line
			(start -0.3 -0.7)
			(end 0.3 -0.7)
			(stroke
				(width 0.15)
				(type solid)
			)
			(layer "F.SilkS")
		)
		(fp_line
			(start -0.3 0.7)
			(end 0.3 0.7)
			(stroke
				(width 0.15)
				(type solid)
			)
			(layer "F.SilkS")
		)
		(fp_rect
			(start 1.95 -0.9)
			(end -1.95 0.9)
			(stroke
				(width 0.05)
				(type default)
			)
			(fill no)
			(layer "F.CrtYd")
		)
		(fp_rect
			(start -0.95 -0.675)
			(end 0.95 0.675)
			(stroke
				(width 0.15)
				(type solid)
			)
			(fill no)
			(layer "F.Fab")
		)
		(pad "1" smd roundrect
			(at -1.1 0 90)
			(size 1.2 1.3)
			(layers "F.Cu" "F.Mask" "F.Paste")
			(roundrect_rratio 0.25)
			(net 28 "GND")
			(pintype "passive")
		)
		(pad "2" smd roundrect
			(at 1.1 0 90)
			(size 1.2 1.3)
			(layers "F.Cu" "F.Mask" "F.Paste")
			(roundrect_rratio 0.25)
			(net 14 "P1_AVDDL")
			(pintype "passive")
		)
	)
	(footprint "antmicro-footprints:R_0402_1005Metric"
		(layer "F.Cu")
		(at 97.4 103.3 180)
		(descr "Resistor SMD 0402")
		(tags "resistor SMD 0402")
		(property "Reference" "R107"
			(at 2.25 -15.05 0)
			(layer "F.SilkS")
			(effects
				(font
					(size 0.7 0.7)
					(thickness 0.15)
				)
				(justify left bottom)
			)
		)
		(property "Value" "R_100R_0402"
			(at -1.011843 1.772046 0)
			(layer "F.Fab")
			(hide yes)
			(effects
				(font
					(size 0.7 0.7)
					(thickness 0.15)
				)
				(justify right top)
			)
		)
		(property "Datasheet" "https://www.bourns.com/docs/product-datasheets/cr.pdf"
			(at 0 0 0)
			(layer "F.Fab")
			(hide yes)
			(effects
				(font
					(size 1.27 1.27)
					(thickness 0.15)
				)
			)
		)
		(property "Description" "SMD Chip Resistor, 100 ohm, ± 1%, 62.5 mW, 0402 [1005 Metric], Thick Film, General Purpose"
			(at 0 0 0)
			(layer "F.Fab")
			(hide yes)
			(effects
				(font
					(size 1.27 1.27)
					(thickness 0.15)
				)
			)
		)
		(property "MPN" "CR0402-FX-1000GLF"
			(at 0 0 180)
			(unlocked yes)
			(layer "F.Fab")
			(hide yes)
			(effects
				(font
					(size 1 1)
					(thickness 0.15)
				)
			)
		)
		(property "Manufacturer" "Bourns"
			(at 0 0 180)
			(unlocked yes)
			(layer "F.Fab")
			(hide yes)
			(effects
				(font
					(size 1 1)
					(thickness 0.15)
				)
			)
		)
		(property "License" "Apache-2.0"
			(at 0 0 180)
			(unlocked yes)
			(layer "F.Fab")
			(hide yes)
			(effects
				(font
					(size 1 1)
					(thickness 0.15)
				)
			)
		)
		(property "Author" "Antmicro"
			(at 0 0 180)
			(unlocked yes)
			(layer "F.Fab")
			(hide yes)
			(effects
				(font
					(size 1 1)
					(thickness 0.15)
				)
			)
		)
		(property "Val" "100R"
			(at 0 0 180)
			(unlocked yes)
			(layer "F.Fab")
			(hide yes)
			(effects
				(font
					(size 1 1)
					(thickness 0.15)
				)
			)
		)
		(property "Tolerance" "1%"
			(at 0 0 180)
			(unlocked yes)
			(layer "F.Fab")
			(hide yes)
			(effects
				(font
					(size 1 1)
					(thickness 0.15)
				)
			)
		)
		(sheetname "/X710-AT2 Misc/")
		(sheetfile "x710-at2-mics.kicad_sch")
		(attr smd exclude_from_pos_files exclude_from_bom dnp)
		(fp_rect
			(start -0.925 -0.47)
			(end 0.925 0.47)
			(stroke
				(width 0.05)
				(type default)
			)
			(fill no)
			(layer "F.CrtYd")
		)
		(fp_rect
			(start -0.5 -0.25)
			(end 0.5 0.25)
			(stroke
				(width 0.15)
				(type solid)
			)
			(fill no)
			(layer "F.Fab")
		)
		(pad "1" smd roundrect
			(at -0.48 0 180)
			(size 0.59 0.64)
			(layers "F.Cu" "F.Mask" "F.Paste")
			(roundrect_rratio 0.25)
			(net 28 "GND")
			(pintype "passive")
		)
		(pad "2" smd roundrect
			(at 0.48 0 180)
			(size 0.59 0.64)
			(layers "F.Cu" "F.Mask" "F.Paste")
			(roundrect_rratio 0.25)
			(net 100 "/X710-AT2 Misc/AUX_PWR")
			(pintype "passive")
		)
	)
	(footprint "antmicro-footprints:R_0402_1005Metric"
		(layer "F.Cu")
		(at 58.1 85.15 90)
		(descr "Resistor SMD 0402")
		(tags "resistor SMD 0402")
		(property "Reference" "R11"
			(at 0.79 1 90)
			(layer "F.SilkS")
			(effects
				(font
					(size 0.7 0.7)
					(thickness 0.15)
				)
				(justify left bottom)
			)
		)
		(property "Value" "R_100k_0402"
			(at -1.011843 1.772046 90)
			(layer "F.Fab")
			(hide yes)
			(effects
				(font
					(size 0.7 0.7)
					(thickness 0.15)
				)
				(justify left bottom)
			)
		)
		(property "Datasheet" "https://www.bourns.com/docs/product-datasheets/cr.pdf"
			(at 0 0 90)
			(layer "F.Fab")
			(hide yes)
			(effects
				(font
					(size 1.27 1.27)
					(thickness 0.15)
				)
			)
		)
		(property "Description" "SMD Chip Resistor, 100 kohm, ± 1%, 62.5 mW, 0402 [1005 Metric], Thick Film, General Purpose"
			(at 0 0 90)
			(layer "F.Fab")
			(hide yes)
			(effects
				(font
					(size 1.27 1.27)
					(thickness 0.15)
				)
			)
		)
		(property "MPN" "CR0402-FX-1003GLF"
			(at 0 0 90)
			(unlocked yes)
			(layer "F.Fab")
			(hide yes)
			(effects
				(font
					(size 1 1)
					(thickness 0.15)
				)
			)
		)
		(property "Manufacturer" "Bourns"
			(at 0 0 90)
			(unlocked yes)
			(layer "F.Fab")
			(hide yes)
			(effects
				(font
					(size 1 1)
					(thickness 0.15)
				)
			)
		)
		(property "License" "Apache-2.0"
			(at 0 0 90)
			(unlocked yes)
			(layer "F.Fab")
			(hide yes)
			(effects
				(font
					(size 1 1)
					(thickness 0.15)
				)
			)
		)
		(property "Author" "Antmicro"
			(at 0 0 90)
			(unlocked yes)
			(layer "F.Fab")
			(hide yes)
			(effects
				(font
					(size 1 1)
					(thickness 0.15)
				)
			)
		)
		(property "Val" "100k"
			(at 0 0 90)
			(unlocked yes)
			(layer "F.Fab")
			(hide yes)
			(effects
				(font
					(size 1 1)
					(thickness 0.15)
				)
			)
		)
		(property "Tolerance" "1%"
			(at 0 0 90)
			(unlocked yes)
			(layer "F.Fab")
			(hide yes)
			(effects
				(font
					(size 1 1)
					(thickness 0.15)
				)
			)
		)
		(sheetname "/Power/")
		(sheetfile "power.kicad_sch")
		(attr smd)
		(fp_rect
			(start -0.925 -0.47)
			(end 0.925 0.47)
			(stroke
				(width 0.05)
				(type default)
			)
			(fill no)
			(layer "F.CrtYd")
		)
		(fp_rect
			(start -0.5 -0.25)
			(end 0.5 0.25)
			(stroke
				(width 0.15)
				(type solid)
			)
			(fill no)
			(layer "F.Fab")
		)
		(pad "1" smd roundrect
			(at -0.48 0 90)
			(size 0.59 0.64)
			(layers "F.Cu" "F.Mask" "F.Paste")
			(roundrect_rratio 0.25)
			(net 342 "/Power/VCCD_PG")
			(pintype "passive")
		)
		(pad "2" smd roundrect
			(at 0.48 0 90)
			(size 0.59 0.64)
			(layers "F.Cu" "F.Mask" "F.Paste")
			(roundrect_rratio 0.25)
			(net 322 "/Power/VCCD_VCC")
			(pintype "passive")
		)
	)
	(footprint "antmicro-footprints:R_0402_1005Metric"
		(layer "F.Cu")
		(at 104.625001 93.45 -90)
		(descr "Resistor SMD 0402")
		(tags "resistor SMD 0402")
		(property "Reference" "R114"
			(at 0.85 0.525001 90)
			(layer "F.SilkS")
			(effects
				(font
					(size 0.7 0.7)
					(thickness 0.15)
				)
				(justify left bottom)
			)
		)
		(property "Value" "R_2k_0402"
			(at -1.011843 1.772046 90)
			(layer "F.Fab")
			(hide yes)
			(effects
				(font
					(size 0.7 0.7)
					(thickness 0.15)
				)
				(justify right top)
			)
		)
		(property "Datasheet" "https://www.bourns.com/docs/product-datasheets/cr.pdf"
			(at 0 0 90)
			(layer "F.Fab")
			(hide yes)
			(effects
				(font
					(size 1.27 1.27)
					(thickness 0.15)
				)
			)
		)
		(property "Description" "SMD Chip Resistor, 2 kohm, ± 1%, 62.5 mW, 0402 [1005 Metric], Thick Film, General Purpose"
			(at 0 0 90)
			(layer "F.Fab")
			(hide yes)
			(effects
				(font
					(size 1.27 1.27)
					(thickness 0.15)
				)
			)
		)
		(property "MPN" "CR0402-FX-2001GLF"
			(at 0 0 270)
			(unlocked yes)
			(layer "F.Fab")
			(hide yes)
			(effects
				(font
					(size 1 1)
					(thickness 0.15)
				)
			)
		)
		(property "Manufacturer" "Bourns"
			(at 0 0 270)
			(unlocked yes)
			(layer "F.Fab")
			(hide yes)
			(effects
				(font
					(size 1 1)
					(thickness 0.15)
				)
			)
		)
		(property "License" "Apache-2.0"
			(at 0 0 270)
			(unlocked yes)
			(layer "F.Fab")
			(hide yes)
			(effects
				(font
					(size 1 1)
					(thickness 0.15)
				)
			)
		)
		(property "Author" "Antmicro"
			(at 0 0 270)
			(unlocked yes)
			(layer "F.Fab")
			(hide yes)
			(effects
				(font
					(size 1 1)
					(thickness 0.15)
				)
			)
		)
		(property "Val" "2k"
			(at 0 0 270)
			(unlocked yes)
			(layer "F.Fab")
			(hide yes)
			(effects
				(font
					(size 1 1)
					(thickness 0.15)
				)
			)
		)
		(property "Tolerance" "1%"
			(at 0 0 270)
			(unlocked yes)
			(layer "F.Fab")
			(hide yes)
			(effects
				(font
					(size 1 1)
					(thickness 0.15)
				)
			)
		)
		(sheetname "/X710-AT2 Misc/")
		(sheetfile "x710-at2-mics.kicad_sch")
		(attr smd)
		(fp_rect
			(start -0.925 -0.47)
			(end 0.925 0.47)
			(stroke
				(width 0.05)
				(type default)
			)
			(fill no)
			(layer "F.CrtYd")
		)
		(fp_rect
			(start -0.5 -0.25)
			(end 0.5 0.25)
			(stroke
				(width 0.15)
				(type solid)
			)
			(fill no)
			(layer "F.Fab")
		)
		(pad "1" smd roundrect
			(at -0.48 0 270)
			(size 0.59 0.64)
			(layers "F.Cu" "F.Mask" "F.Paste")
			(roundrect_rratio 0.25)
			(net 381 "/X710-AT2 Misc/MDIO.MDIO")
			(pintype "passive")
		)
		(pad "2" smd roundrect
			(at 0.48 0 270)
			(size 0.59 0.64)
			(layers "F.Cu" "F.Mask" "F.Paste")
			(roundrect_rratio 0.25)
			(net 18 "+1V88")
			(pintype "passive")
		)
	)
	(footprint "antmicro-footprints:R_0402_1005Metric"
		(layer "F.Cu")
		(at 87.1 112.45 90)
		(descr "Resistor SMD 0402")
		(tags "resistor SMD 0402")
		(property "Reference" "R74"
			(at -0.85 0.4375 90)
			(layer "F.SilkS")
			(effects
				(font
					(size 0.7 0.7)
					(thickness 0.15)
				)
				(justify right bottom)
			)
		)
		(property "Value" "R_0R_0402"
			(at -1.011843 1.772046 90)
			(layer "F.Fab")
			(hide yes)
			(effects
				(font
					(size 0.7 0.7)
					(thickness 0.15)
				)
				(justify left bottom)
			)
		)
		(property "Datasheet" "https://industrial.panasonic.com/cdbs/www-data/pdf/RDA0000/AOA0000C301.pdf"
			(at 0 0 90)
			(layer "F.Fab")
			(hide yes)
			(effects
				(font
					(size 1.27 1.27)
					(thickness 0.15)
				)
			)
		)
		(property "Description" "SMD Chip Resistor, Jumper, 0 ohm, 100 mW, 0402 [1005 Metric], Thick Film, General Purpose"
			(at 0 0 90)
			(layer "F.Fab")
			(hide yes)
			(effects
				(font
					(size 1.27 1.27)
					(thickness 0.15)
				)
			)
		)
		(property "MPN" "ERJ2GE0R00X"
			(at 0 0 90)
			(unlocked yes)
			(layer "F.Fab")
			(hide yes)
			(effects
				(font
					(size 1 1)
					(thickness 0.15)
				)
			)
		)
		(property "Manufacturer" "Panasonic"
			(at 0 0 90)
			(unlocked yes)
			(layer "F.Fab")
			(hide yes)
			(effects
				(font
					(size 1 1)
					(thickness 0.15)
				)
			)
		)
		(property "License" "Apache-2.0"
			(at 0 0 90)
			(unlocked yes)
			(layer "F.Fab")
			(hide yes)
			(effects
				(font
					(size 1 1)
					(thickness 0.15)
				)
			)
		)
		(property "Author" "Antmicro"
			(at 0 0 90)
			(unlocked yes)
			(layer "F.Fab")
			(hide yes)
			(effects
				(font
					(size 1 1)
					(thickness 0.15)
				)
			)
		)
		(property "Val" "0R"
			(at 0 0 90)
			(unlocked yes)
			(layer "F.Fab")
			(hide yes)
			(effects
				(font
					(size 1 1)
					(thickness 0.15)
				)
			)
		)
		(property "Tolerance" "~"
			(at 0 0 90)
			(unlocked yes)
			(layer "F.Fab")
			(hide yes)
			(effects
				(font
					(size 1 1)
					(thickness 0.15)
				)
			)
		)
		(property "Current" "1A"
			(at 0 0 90)
			(unlocked yes)
			(layer "F.Fab")
			(hide yes)
			(effects
				(font
					(size 1 1)
					(thickness 0.15)
				)
			)
		)
		(sheetname "/X710-AT2 10GbE/")
		(sheetfile "x710-at2-10gbe.kicad_sch")
		(attr smd)
		(fp_rect
			(start -0.925 -0.47)
			(end 0.925 0.47)
			(stroke
				(width 0.05)
				(type default)
			)
			(fill no)
			(layer "F.CrtYd")
		)
		(fp_rect
			(start -0.5 -0.25)
			(end 0.5 0.25)
			(stroke
				(width 0.15)
				(type solid)
			)
			(fill no)
			(layer "F.Fab")
		)
		(pad "1" smd roundrect
			(at -0.48 0 90)
			(size 0.59 0.64)
			(layers "F.Cu" "F.Mask" "F.Paste")
			(roundrect_rratio 0.25)
			(net 28 "GND")
			(pintype "passive")
		)
		(pad "2" smd roundrect
			(at 0.48 0 90)
			(size 0.59 0.64)
			(layers "F.Cu" "F.Mask" "F.Paste")
			(roundrect_rratio 0.25)
			(net 293 "/X710-AT2 10GbE/TPIN_3")
			(pintype "passive")
		)
	)
	(footprint "antmicro-footprints:FB_0603_1608Metric"
		(layer "F.Cu")
		(at 69.1 95.35)
		(property "Reference" "FB3"
			(at -0.79 -0.53 0)
			(layer "F.SilkS")
			(effects
				(font
					(size 0.7 0.7)
					(thickness 0.15)
				)
				(justify left bottom)
			)
		)
		(property "Value" "FB_470Z_1A_Murata-BLM18PG_0603"
			(at 0 1.5 0)
			(layer "F.Fab")
			(hide yes)
			(effects
				(font
					(size 0.7 0.7)
					(thickness 0.15)
				)
				(justify left bottom)
			)
		)
		(property "Datasheet" "https://www.murata.com/en-us/products/productdata/8796738650142/ENFA0003.pdf"
			(at 0 0 0)
			(layer "F.Fab")
			(hide yes)
			(effects
				(font
					(size 1.27 1.27)
					(thickness 0.15)
				)
			)
		)
		(property "Description" "Ferrite Bead, 0603 [1608 Metric], 470 ohm, 1 A, BLM18P, 0.2 ohm, ± 25%, DC power line"
			(at 0 0 0)
			(layer "F.Fab")
			(hide yes)
			(effects
				(font
					(size 1.27 1.27)
					(thickness 0.15)
				)
			)
		)
		(property "Val" "470Z/1A"
			(at 0 0 0)
			(unlocked yes)
			(layer "F.Fab")
			(hide yes)
			(effects
				(font
					(size 1 1)
					(thickness 0.15)
				)
			)
		)
		(property "MPN" "BLM18PG471SN1D"
			(at 0 0 0)
			(unlocked yes)
			(layer "F.Fab")
			(hide yes)
			(effects
				(font
					(size 1 1)
					(thickness 0.15)
				)
			)
		)
		(property "Manufacturer" "Murata"
			(at 0 0 0)
			(unlocked yes)
			(layer "F.Fab")
			(hide yes)
			(effects
				(font
					(size 1 1)
					(thickness 0.15)
				)
			)
		)
		(property "Current" ""
			(at 0 0 0)
			(unlocked yes)
			(layer "F.Fab")
			(hide yes)
			(effects
				(font
					(size 1 1)
					(thickness 0.15)
				)
			)
		)
		(property "Author" "Antmicro"
			(at 0 0 0)
			(unlocked yes)
			(layer "F.Fab")
			(hide yes)
			(effects
				(font
					(size 1 1)
					(thickness 0.15)
				)
			)
		)
		(property "License" "Apache-2.0"
			(at 0 0 0)
			(unlocked yes)
			(layer "F.Fab")
			(hide yes)
			(effects
				(font
					(size 1 1)
					(thickness 0.15)
				)
			)
		)
		(sheetname "/X710-AT2 power/")
		(sheetfile "x710-at2-power.kicad_sch")
		(attr smd)
		(fp_line
			(start -0.15 -0.4)
			(end 0.15 -0.4)
			(stroke
				(width 0.15)
				(type solid)
			)
			(layer "F.SilkS")
		)
		(fp_line
			(start -0.15 0.4)
			(end 0.15 0.4)
			(stroke
				(width 0.15)
				(type solid)
			)
			(layer "F.SilkS")
		)
		(fp_rect
			(start -1.25 -0.65)
			(end 1.25 0.65)
			(stroke
				(width 0.05)
				(type solid)
			)
			(fill no)
			(layer "F.CrtYd")
		)
		(fp_line
			(start -0.803 0.406)
			(end -0.803 -0.408)
			(stroke
				(width 0.15)
				(type solid)
			)
			(layer "F.Fab")
		)
		(fp_line
			(start 0.8 -0.408)
			(end -0.803 -0.408)
			(stroke
				(width 0.15)
				(type solid)
			)
			(layer "F.Fab")
		)
		(fp_line
			(start 0.8 -0.408)
			(end 0.8 0.406)
			(stroke
				(width 0.15)
				(type solid)
			)
			(layer "F.Fab")
		)
		(fp_line
			(start 0.8 0.406)
			(end -0.803 0.406)
			(stroke
				(width 0.15)
				(type solid)
			)
			(layer "F.Fab")
		)
		(pad "1" smd roundrect
			(at -0.7 0)
			(size 0.8 1)
			(layers "F.Cu" "F.Mask" "F.Paste")
			(roundrect_rratio 0.2)
			(net 18 "+1V88")
			(pintype "passive")
		)
		(pad "2" smd roundrect
			(at 0.7 0)
			(size 0.8 1)
			(layers "F.Cu" "F.Mask" "F.Paste")
			(roundrect_rratio 0.2)
			(net 23 "XGB_AVDDH")
			(pintype "passive")
		)
	)
)
